(kicad_pcb
	(version 20260206)
	(generator "pcbnew")
	(generator_version "10.0")
	(general
		(thickness 1.6)
		(legacy_teardrops no)
	)
	(paper "A4")
	(title_block
		(title "01162023_DA0F0TEBIF0_F0T_Expander_BD_F_brd_V02_OCP.brd")
		(comment 1 "Grand Teton / footprints 582-589 of 9728")
	)
	(layers
		(0 "F.Cu" signal "TOP")
		(4 "In1.Cu" signal "GND")
		(6 "In2.Cu" signal "VCC")
		(8 "In3.Cu" signal "VCC1")
		(10 "In4.Cu" signal "GND1")
		(12 "In5.Cu" signal "IN1")
		(14 "In6.Cu" signal "GND2")
		(16 "In7.Cu" signal "IN2")
		(18 "In8.Cu" signal "GND3")
		(20 "In9.Cu" signal "IN3")
		(22 "In10.Cu" signal "GND4")
		(24 "In11.Cu" signal "IN4")
		(26 "In12.Cu" signal "GND5")
		(28 "In13.Cu" signal "IN5")
		(30 "In14.Cu" signal "GND6")
		(32 "In15.Cu" signal "IN6")
		(34 "In16.Cu" signal "GND7")
		(2 "B.Cu" signal "BOTTOM")
		(9 "F.Adhes" user "F.Adhesive")
		(11 "B.Adhes" user "B.Adhesive")
		(13 "F.Paste" user "Package Geometry/Pastemask Top")
		(15 "B.Paste" user "Package Geometry/Pastemask Bottom")
		(5 "F.SilkS" user "Ref Des/Silkscreen Top")
		(7 "B.SilkS" user "Ref Des/Silkscreen Bottom")
		(1 "F.Mask" user "Board Geometry/Soldermask Top")
		(3 "B.Mask" user "Board Geometry/Soldermask Bottom")
		(17 "Dwgs.User" user "User.Drawings")
		(19 "Cmts.User" user "User.Comments")
		(21 "Eco1.User" user "User.Eco1")
		(23 "Eco2.User" user "User.Eco2")
		(25 "Edge.Cuts" user "Board Geometry/Outline")
		(27 "Margin" user)
		(31 "F.CrtYd" user "Package Geometry/Place Bound Top")
		(29 "B.CrtYd" user "Package Geometry/Place Bound Bottom")
		(35 "F.Fab" user "Ref Des/Assembly Top")
		(33 "B.Fab" user "Ref Des/Assembly Bottom")
	)
	(footprint ""
		(layer "F.Cu")
		(at 266.702286 -252.356874 -90)
		(property "Reference" "R1367"
			(at 0 0 270)
			(layer "F.SilkS")
			(hide yes)
			(effects
				(font
					(size 1.27 1.27)
				)
			)
		)
		(property "Value" ""
			(at 0 0 270)
			(layer "F.Fab")
			(effects
				(font
					(size 1.27 1.27)
				)
			)
		)
		(duplicate_pad_numbers_are_jumpers no)
		(fp_line
			(start -0.7874 0.4064)
			(end -0.7874 -0.4064)
			(stroke
				(width 0.1524)
				(type default)
			)
			(layer "F.SilkS")
		)
		(fp_line
			(start 0.7874 0.4064)
			(end -0.7874 0.4064)
			(stroke
				(width 0.1524)
				(type default)
			)
			(layer "F.SilkS")
		)
		(fp_line
			(start -0.7874 -0.4064)
			(end 0.7874 -0.4064)
			(stroke
				(width 0.1524)
				(type default)
			)
			(layer "F.SilkS")
		)
		(fp_line
			(start 0.7874 -0.4064)
			(end 0.7874 0.4064)
			(stroke
				(width 0.1524)
				(type default)
			)
			(layer "F.SilkS")
		)
		(fp_line
			(start -0.67945 0.3048)
			(end -0.67945 -0.305054)
			(stroke
				(width 0.1)
				(type default)
			)
			(layer "F.Fab")
		)
		(fp_line
			(start -0.12065 0.3048)
			(end -0.67945 0.3048)
			(stroke
				(width 0.1)
				(type default)
			)
			(layer "F.Fab")
		)
		(fp_line
			(start 0.120396 0.3048)
			(end 0.120396 0.2794)
			(stroke
				(width 0.1)
				(type default)
			)
			(layer "F.Fab")
		)
		(fp_line
			(start 0.67945 0.3048)
			(end 0.120396 0.3048)
			(stroke
				(width 0.1)
				(type default)
			)
			(layer "F.Fab")
		)
		(fp_line
			(start -0.12065 0.2794)
			(end -0.12065 0.3048)
			(stroke
				(width 0.1)
				(type default)
			)
			(layer "F.Fab")
		)
		(fp_line
			(start 0.120396 0.2794)
			(end -0.12065 0.2794)
			(stroke
				(width 0.1)
				(type default)
			)
			(layer "F.Fab")
		)
		(fp_line
			(start -0.12065 -0.2794)
			(end 0.12065 -0.2794)
			(stroke
				(width 0.1)
				(type default)
			)
			(layer "F.Fab")
		)
		(fp_line
			(start 0.12065 -0.2794)
			(end 0.12065 -0.3048)
			(stroke
				(width 0.1)
				(type default)
			)
			(layer "F.Fab")
		)
		(fp_line
			(start 0.12065 -0.3048)
			(end 0.67945 -0.3048)
			(stroke
				(width 0.1)
				(type default)
			)
			(layer "F.Fab")
		)
		(fp_line
			(start 0.67945 -0.3048)
			(end 0.67945 0.3048)
			(stroke
				(width 0.1)
				(type default)
			)
			(layer "F.Fab")
		)
		(fp_line
			(start -0.67945 -0.305054)
			(end -0.12065 -0.305054)
			(stroke
				(width 0.1)
				(type default)
			)
			(layer "F.Fab")
		)
		(fp_line
			(start -0.12065 -0.305054)
			(end -0.12065 -0.2794)
			(stroke
				(width 0.1)
				(type default)
			)
			(layer "F.Fab")
		)
		(pad "1" smd circle
			(at -0.40005 0 270)
			(size 0 0)
			(layers "F.Cu" "F.Mask" "F.Paste")
			(net "GND")
		)
		(pad "2" smd circle
			(at 0.40005 0 270)
			(size 0 0)
			(layers "F.Cu" "F.Mask" "F.Paste")
			(net "PEX2_MODE_SEL11")
		)
	)
	(footprint ""
		(layer "F.Cu")
		(at 71.796148 -47.20082 90)
		(property "Reference" "C208"
			(at 0 0 90)
			(layer "F.SilkS")
			(hide yes)
			(effects
				(font
					(size 1.27 1.27)
				)
			)
		)
		(property "Value" ""
			(at 0 0 90)
			(layer "F.Fab")
			(effects
				(font
					(size 1.27 1.27)
				)
			)
		)
		(duplicate_pad_numbers_are_jumpers no)
		(fp_line
			(start 0.7874 -0.4064)
			(end 0.7874 0.4064)
			(stroke
				(width 0.1524)
				(type default)
			)
			(layer "F.SilkS")
		)
		(fp_line
			(start -0.7874 -0.4064)
			(end 0.7874 -0.4064)
			(stroke
				(width 0.1524)
				(type default)
			)
			(layer "F.SilkS")
		)
		(fp_line
			(start 0.7874 0.4064)
			(end -0.7874 0.4064)
			(stroke
				(width 0.1524)
				(type default)
			)
			(layer "F.SilkS")
		)
		(fp_line
			(start -0.7874 0.4064)
			(end -0.7874 -0.4064)
			(stroke
				(width 0.1524)
				(type default)
			)
			(layer "F.SilkS")
		)
		(fp_line
			(start -0.12065 -0.305054)
			(end -0.12065 -0.2794)
			(stroke
				(width 0.1)
				(type default)
			)
			(layer "F.Fab")
		)
		(fp_line
			(start -0.67945 -0.305054)
			(end -0.12065 -0.305054)
			(stroke
				(width 0.1)
				(type default)
			)
			(layer "F.Fab")
		)
		(fp_line
			(start 0.67945 -0.3048)
			(end 0.67945 0.3048)
			(stroke
				(width 0.1)
				(type default)
			)
			(layer "F.Fab")
		)
		(fp_line
			(start 0.12065 -0.3048)
			(end 0.67945 -0.3048)
			(stroke
				(width 0.1)
				(type default)
			)
			(layer "F.Fab")
		)
		(fp_line
			(start 0.12065 -0.2794)
			(end 0.12065 -0.3048)
			(stroke
				(width 0.1)
				(type default)
			)
			(layer "F.Fab")
		)
		(fp_line
			(start -0.12065 -0.2794)
			(end 0.12065 -0.2794)
			(stroke
				(width 0.1)
				(type default)
			)
			(layer "F.Fab")
		)
		(fp_line
			(start 0.120396 0.2794)
			(end -0.12065 0.2794)
			(stroke
				(width 0.1)
				(type default)
			)
			(layer "F.Fab")
		)
		(fp_line
			(start -0.12065 0.2794)
			(end -0.12065 0.3048)
			(stroke
				(width 0.1)
				(type default)
			)
			(layer "F.Fab")
		)
		(fp_line
			(start 0.67945 0.3048)
			(end 0.120396 0.3048)
			(stroke
				(width 0.1)
				(type default)
			)
			(layer "F.Fab")
		)
		(fp_line
			(start 0.120396 0.3048)
			(end 0.120396 0.2794)
			(stroke
				(width 0.1)
				(type default)
			)
			(layer "F.Fab")
		)
		(fp_line
			(start -0.12065 0.3048)
			(end -0.67945 0.3048)
			(stroke
				(width 0.1)
				(type default)
			)
			(layer "F.Fab")
		)
		(fp_line
			(start -0.67945 0.3048)
			(end -0.67945 -0.305054)
			(stroke
				(width 0.1)
				(type default)
			)
			(layer "F.Fab")
		)
		(pad "1" smd circle
			(at -0.40005 0 90)
			(size 0 0)
			(layers "F.Cu" "F.Mask" "F.Paste")
			(net "P12V_SSD2_R")
		)
		(pad "2" smd circle
			(at 0.40005 0 90)
			(size 0 0)
			(layers "F.Cu" "F.Mask" "F.Paste")
			(net "GND")
		)
	)
	(footprint ""
		(layer "F.Cu")
		(at 16.785336 -272.200624)
		(property "Reference" "R773"
			(at 0 0 0)
			(layer "F.SilkS")
			(hide yes)
			(effects
				(font
					(size 1.27 1.27)
				)
			)
		)
		(property "Value" ""
			(at 0 0 0)
			(layer "F.Fab")
			(effects
				(font
					(size 1.27 1.27)
				)
			)
		)
		(duplicate_pad_numbers_are_jumpers no)
		(fp_line
			(start -0.7874 -0.4064)
			(end 0.7874 -0.4064)
			(stroke
				(width 0.1524)
				(type default)
			)
			(layer "F.SilkS")
		)
		(fp_line
			(start -0.7874 0.4064)
			(end -0.7874 -0.4064)
			(stroke
				(width 0.1524)
				(type default)
			)
			(layer "F.SilkS")
		)
		(fp_line
			(start 0.7874 -0.4064)
			(end 0.7874 0.4064)
			(stroke
				(width 0.1524)
				(type default)
			)
			(layer "F.SilkS")
		)
		(fp_line
			(start 0.7874 0.4064)
			(end -0.7874 0.4064)
			(stroke
				(width 0.1524)
				(type default)
			)
			(layer "F.SilkS")
		)
		(fp_line
			(start -0.67945 -0.305054)
			(end -0.12065 -0.305054)
			(stroke
				(width 0.1)
				(type default)
			)
			(layer "F.Fab")
		)
		(fp_line
			(start -0.67945 0.3048)
			(end -0.67945 -0.305054)
			(stroke
				(width 0.1)
				(type default)
			)
			(layer "F.Fab")
		)
		(fp_line
			(start -0.12065 -0.305054)
			(end -0.12065 -0.2794)
			(stroke
				(width 0.1)
				(type default)
			)
			(layer "F.Fab")
		)
		(fp_line
			(start -0.12065 -0.2794)
			(end 0.12065 -0.2794)
			(stroke
				(width 0.1)
				(type default)
			)
			(layer "F.Fab")
		)
		(fp_line
			(start -0.12065 0.2794)
			(end -0.12065 0.3048)
			(stroke
				(width 0.1)
				(type default)
			)
			(layer "F.Fab")
		)
		(fp_line
			(start -0.12065 0.3048)
			(end -0.67945 0.3048)
			(stroke
				(width 0.1)
				(type default)
			)
			(layer "F.Fab")
		)
		(fp_line
			(start 0.120396 0.2794)
			(end -0.12065 0.2794)
			(stroke
				(width 0.1)
				(type default)
			)
			(layer "F.Fab")
		)
		(fp_line
			(start 0.120396 0.3048)
			(end 0.120396 0.2794)
			(stroke
				(width 0.1)
				(type default)
			)
			(layer "F.Fab")
		)
		(fp_line
			(start 0.12065 -0.3048)
			(end 0.67945 -0.3048)
			(stroke
				(width 0.1)
				(type default)
			)
			(layer "F.Fab")
		)
		(fp_line
			(start 0.12065 -0.2794)
			(end 0.12065 -0.3048)
			(stroke
				(width 0.1)
				(type default)
			)
			(layer "F.Fab")
		)
		(fp_line
			(start 0.67945 -0.3048)
			(end 0.67945 0.3048)
			(stroke
				(width 0.1)
				(type default)
			)
			(layer "F.Fab")
		)
		(fp_line
			(start 0.67945 0.3048)
			(end 0.120396 0.3048)
			(stroke
				(width 0.1)
				(type default)
			)
			(layer "F.Fab")
		)
		(pad "1" smd circle
			(at -0.40005 0)
			(size 0 0)
			(layers "F.Cu" "F.Mask" "F.Paste")
			(net "PEX0_P1V25_ADC_A1")
		)
		(pad "2" smd circle
			(at 0.40005 0)
			(size 0 0)
			(layers "F.Cu" "F.Mask" "F.Paste")
			(net "GND")
		)
	)
	(footprint ""
		(layer "F.Cu")
		(at 186.047126 -55.63489 90)
		(property "Reference" "PC383"
			(at 0 0 90)
			(layer "F.SilkS")
			(hide yes)
			(effects
				(font
					(size 1.27 1.27)
				)
			)
		)
		(property "Value" ""
			(at 0 0 90)
			(layer "F.Fab")
			(effects
				(font
					(size 1.27 1.27)
				)
			)
		)
		(duplicate_pad_numbers_are_jumpers no)
		(fp_line
			(start 1.524 -0.762)
			(end 1.524 0.762)
			(stroke
				(width 0.1524)
				(type default)
			)
			(layer "F.SilkS")
		)
		(fp_line
			(start -1.524 -0.762)
			(end 1.524 -0.762)
			(stroke
				(width 0.1524)
				(type default)
			)
			(layer "F.SilkS")
		)
		(fp_line
			(start 1.524 0.762)
			(end -1.524 0.762)
			(stroke
				(width 0.1524)
				(type default)
			)
			(layer "F.SilkS")
		)
		(fp_line
			(start -1.524 0.762)
			(end -1.524 -0.762)
			(stroke
				(width 0.1524)
				(type default)
			)
			(layer "F.SilkS")
		)
		(fp_line
			(start 1.1049 -0.724916)
			(end -1.1049 -0.724916)
			(stroke
				(width 0.1)
				(type default)
			)
			(layer "F.Fab")
		)
		(fp_line
			(start -1.1049 -0.724916)
			(end -1.1049 0.724916)
			(stroke
				(width 0.1)
				(type default)
			)
			(layer "F.Fab")
		)
		(fp_line
			(start 1.1049 0.724916)
			(end 1.1049 -0.724916)
			(stroke
				(width 0.1)
				(type default)
			)
			(layer "F.Fab")
		)
		(fp_line
			(start -1.1049 0.724916)
			(end 1.1049 0.724916)
			(stroke
				(width 0.1)
				(type default)
			)
			(layer "F.Fab")
		)
		(pad "1" smd rect
			(at -0.889 0 270)
			(size 1.016 1.27)
			(layers "F.Cu" "F.Mask" "F.Paste")
			(net "P12V_SSD6_R")
		)
		(pad "2" smd rect
			(at 0.889 0 270)
			(size 1.016 1.27)
			(layers "F.Cu" "F.Mask" "F.Paste")
			(net "GND")
		)
	)
	(footprint ""
		(layer "F.Cu")
		(at 248.094754 -275.503386)
		(property "Reference" "R791"
			(at 0 0 0)
			(layer "F.SilkS")
			(hide yes)
			(effects
				(font
					(size 1.27 1.27)
				)
			)
		)
		(property "Value" ""
			(at 0 0 0)
			(layer "F.Fab")
			(effects
				(font
					(size 1.27 1.27)
				)
			)
		)
		(duplicate_pad_numbers_are_jumpers no)
		(fp_line
			(start -0.7874 -0.4064)
			(end 0.7874 -0.4064)
			(stroke
				(width 0.1524)
				(type default)
			)
			(layer "F.SilkS")
		)
		(fp_line
			(start -0.7874 0.4064)
			(end -0.7874 -0.4064)
			(stroke
				(width 0.1524)
				(type default)
			)
			(layer "F.SilkS")
		)
		(fp_line
			(start 0.7874 -0.4064)
			(end 0.7874 0.4064)
			(stroke
				(width 0.1524)
				(type default)
			)
			(layer "F.SilkS")
		)
		(fp_line
			(start 0.7874 0.4064)
			(end -0.7874 0.4064)
			(stroke
				(width 0.1524)
				(type default)
			)
			(layer "F.SilkS")
		)
		(fp_line
			(start -0.67945 -0.305054)
			(end -0.12065 -0.305054)
			(stroke
				(width 0.1)
				(type default)
			)
			(layer "F.Fab")
		)
		(fp_line
			(start -0.67945 0.3048)
			(end -0.67945 -0.305054)
			(stroke
				(width 0.1)
				(type default)
			)
			(layer "F.Fab")
		)
		(fp_line
			(start -0.12065 -0.305054)
			(end -0.12065 -0.2794)
			(stroke
				(width 0.1)
				(type default)
			)
			(layer "F.Fab")
		)
		(fp_line
			(start -0.12065 -0.2794)
			(end 0.12065 -0.2794)
			(stroke
				(width 0.1)
				(type default)
			)
			(layer "F.Fab")
		)
		(fp_line
			(start -0.12065 0.2794)
			(end -0.12065 0.3048)
			(stroke
				(width 0.1)
				(type default)
			)
			(layer "F.Fab")
		)
		(fp_line
			(start -0.12065 0.3048)
			(end -0.67945 0.3048)
			(stroke
				(width 0.1)
				(type default)
			)
			(layer "F.Fab")
		)
		(fp_line
			(start 0.120396 0.2794)
			(end -0.12065 0.2794)
			(stroke
				(width 0.1)
				(type default)
			)
			(layer "F.Fab")
		)
		(fp_line
			(start 0.120396 0.3048)
			(end 0.120396 0.2794)
			(stroke
				(width 0.1)
				(type default)
			)
			(layer "F.Fab")
		)
		(fp_line
			(start 0.12065 -0.3048)
			(end 0.67945 -0.3048)
			(stroke
				(width 0.1)
				(type default)
			)
			(layer "F.Fab")
		)
		(fp_line
			(start 0.12065 -0.2794)
			(end 0.12065 -0.3048)
			(stroke
				(width 0.1)
				(type default)
			)
			(layer "F.Fab")
		)
		(fp_line
			(start 0.67945 -0.3048)
			(end 0.67945 0.3048)
			(stroke
				(width 0.1)
				(type default)
			)
			(layer "F.Fab")
		)
		(fp_line
			(start 0.67945 0.3048)
			(end 0.120396 0.3048)
			(stroke
				(width 0.1)
				(type default)
			)
			(layer "F.Fab")
		)
		(pad "1" smd circle
			(at -0.40005 0)
			(size 0 0)
			(layers "F.Cu" "F.Mask" "F.Paste")
			(net "PEX2_P1V25_ADC_A0")
		)
		(pad "2" smd circle
			(at 0.40005 0)
			(size 0 0)
			(layers "F.Cu" "F.Mask" "F.Paste")
			(net "P3V3_AUX")
		)
	)
	(footprint ""
		(layer "F.Cu")
		(at 480.069906 -524.787368 180)
		(property "Reference" "J35_OTH"
			(at -3.2385 -1.402334 0)
			(unlocked yes)
			(layer "B.SilkS")
			(effects
				(font
					(size 0.7874 0.5842)
					(thickness 0.1524)
				)
				(justify mirror)
			)
		)
		(property "Value" ""
			(at 0 0 180)
			(layer "F.Fab")
			(effects
				(font
					(size 1.27 1.27)
				)
			)
		)
		(duplicate_pad_numbers_are_jumpers no)
		(pad "1" thru_hole circle
			(at 0 0 180)
			(size 0.4572 0.4572)
			(drill 0.2032)
			(layers "*.Cu" "*.Mask")
			(remove_unused_layers no)
			(net "Net_9101")
			(clearance 0.127)
			(thermal_gap 0.127)
			(padstack
				(mode front_inner_back)
				(layer "Inner"
					(shape circle)
					(size 0.4572 0.4572)
					(clearance 0.127)
				)
				(layer "B.Cu"
					(shape circle)
					(size 0.508 0.508)
					(clearance 0.1016)
				)
			)
		)
	)
	(footprint ""
		(layer "F.Cu")
		(at 384.938524 -122.79884)
		(property "Reference" "C676"
			(at 0 0 0)
			(layer "F.SilkS")
			(hide yes)
			(effects
				(font
					(size 1.27 1.27)
				)
			)
		)
		(property "Value" ""
			(at 0 0 0)
			(layer "F.Fab")
			(effects
				(font
					(size 1.27 1.27)
				)
			)
		)
		(duplicate_pad_numbers_are_jumpers no)
		(fp_line
			(start -0.299974 -0.150114)
			(end 0.299974 -0.150114)
			(stroke
				(width 0.1)
				(type default)
			)
			(layer "F.Fab")
		)
		(fp_line
			(start -0.299974 0.150114)
			(end -0.299974 -0.150114)
			(stroke
				(width 0.1)
				(type default)
			)
			(layer "F.Fab")
		)
		(fp_line
			(start 0.299974 -0.150114)
			(end 0.299974 0.150114)
			(stroke
				(width 0.1)
				(type default)
			)
			(layer "F.Fab")
		)
		(fp_line
			(start 0.299974 0.150114)
			(end -0.299974 0.150114)
			(stroke
				(width 0.1)
				(type default)
			)
			(layer "F.Fab")
		)
		(pad "1" smd rect
			(at -0.2667 0)
			(size 0.3048 0.381)
			(layers "F.Cu" "F.Mask" "F.Paste")
			(net "P5E_PEX3_STN1_TX_DP<26>")
		)
		(pad "2" smd rect
			(at 0.2667 0)
			(size 0.3048 0.381)
			(layers "F.Cu" "F.Mask" "F.Paste")
			(net "P5E_PEX3_STN1_TX_C_DP<26>")
		)
	)
	(footprint ""
		(layer "F.Cu")
		(at 210.087972 -45.704252 90)
		(property "Reference" "R583"
			(at 0 0 90)
			(layer "F.SilkS")
			(hide yes)
			(effects
				(font
					(size 1.27 1.27)
				)
			)
		)
		(property "Value" ""
			(at 0 0 90)
			(layer "F.Fab")
			(effects
				(font
					(size 1.27 1.27)
				)
			)
		)
		(duplicate_pad_numbers_are_jumpers no)
		(fp_line
			(start 3.937508 -1.8796)
			(end -3.937508 -1.8796)
			(stroke
				(width 0.1524)
				(type default)
			)
			(layer "F.SilkS")
		)
		(fp_line
			(start -3.937508 -1.8796)
			(end -3.937508 1.8796)
			(stroke
				(width 0.1524)
				(type default)
			)
			(layer "F.SilkS")
		)
		(fp_line
			(start 3.937508 1.8796)
			(end 3.937508 -1.8796)
			(stroke
				(width 0.1524)
				(type default)
			)
			(layer "F.SilkS")
		)
		(fp_line
			(start -3.937508 1.8796)
			(end 3.937508 1.8796)
			(stroke
				(width 0.1524)
				(type default)
			)
			(layer "F.SilkS")
		)
		(fp_line
			(start 3.275076 -1.674876)
			(end -3.275076 -1.674876)
			(stroke
				(width 0.1)
				(type default)
			)
			(layer "F.Fab")
		)
		(fp_line
			(start -3.275076 -1.674876)
			(end -3.275076 1.674876)
			(stroke
				(width 0.1)
				(type default)
			)
			(layer "F.Fab")
		)
		(fp_line
			(start 3.275076 1.674876)
			(end 3.275076 -1.674876)
			(stroke
				(width 0.1)
				(type default)
			)
			(layer "F.Fab")
		)
		(fp_line
			(start -3.275076 1.674876)
			(end 3.275076 1.674876)
			(stroke
				(width 0.1)
				(type default)
			)
			(layer "F.Fab")
		)
		(pad "1" smd rect
			(at -2.350008 0 90)
			(size 2.921 3.5052)
			(layers "F.Cu" "F.Mask" "F.Paste")
			(net "P12V_SSD7")
		)
		(pad "2" smd rect
			(at 2.350008 0 90)
			(size 2.921 3.5052)
			(layers "F.Cu" "F.Mask" "F.Paste")
			(net "P12V_SSD7_R")
		)
	)
)
